(kicad_pcb
	(version 20260206)
	(generator "pcbnew")
	(generator_version "10.0")
	(general
		(thickness 1.6)
		(legacy_teardrops no)
	)
	(paper "A4")
	(title_block
		(title "01162023_DA0F0TEBIF0_F0T_Expander_BD_F_brd_V02_OCP.brd")
		(comment 1 "Grand Teton / footprints 4208-4214 of 9728")
	)
	(layers
		(0 "F.Cu" signal "TOP")
		(4 "In1.Cu" signal "GND")
		(6 "In2.Cu" signal "VCC")
		(8 "In3.Cu" signal "VCC1")
		(10 "In4.Cu" signal "GND1")
		(12 "In5.Cu" signal "IN1")
		(14 "In6.Cu" signal "GND2")
		(16 "In7.Cu" signal "IN2")
		(18 "In8.Cu" signal "GND3")
		(20 "In9.Cu" signal "IN3")
		(22 "In10.Cu" signal "GND4")
		(24 "In11.Cu" signal "IN4")
		(26 "In12.Cu" signal "GND5")
		(28 "In13.Cu" signal "IN5")
		(30 "In14.Cu" signal "GND6")
		(32 "In15.Cu" signal "IN6")
		(34 "In16.Cu" signal "GND7")
		(2 "B.Cu" signal "BOTTOM")
		(9 "F.Adhes" user "F.Adhesive")
		(11 "B.Adhes" user "B.Adhesive")
		(13 "F.Paste" user "Package Geometry/Pastemask Top")
		(15 "B.Paste" user "Package Geometry/Pastemask Bottom")
		(5 "F.SilkS" user "Ref Des/Silkscreen Top")
		(7 "B.SilkS" user "Ref Des/Silkscreen Bottom")
		(1 "F.Mask" user "Board Geometry/Soldermask Top")
		(3 "B.Mask" user "Board Geometry/Soldermask Bottom")
		(17 "Dwgs.User" user "User.Drawings")
		(19 "Cmts.User" user "User.Comments")
		(21 "Eco1.User" user "User.Eco1")
		(23 "Eco2.User" user "User.Eco2")
		(25 "Edge.Cuts" user "Board Geometry/Outline")
		(27 "Margin" user)
		(31 "F.CrtYd" user "Package Geometry/Place Bound Top")
		(29 "B.CrtYd" user "Package Geometry/Place Bound Bottom")
		(35 "F.Fab" user "Ref Des/Assembly Top")
		(33 "B.Fab" user "Ref Des/Assembly Bottom")
	)
	(footprint ""
		(layer "F.Cu")
		(at 332.416404 -100.178108 90)
		(property "Reference" "PC318"
			(at 0 0 90)
			(layer "F.SilkS")
			(hide yes)
			(effects
				(font
					(size 1.27 1.27)
				)
			)
		)
		(property "Value" ""
			(at 0 0 90)
			(layer "F.Fab")
			(effects
				(font
					(size 1.27 1.27)
				)
			)
		)
		(duplicate_pad_numbers_are_jumpers no)
		(fp_line
			(start 0.7874 -0.4064)
			(end 0.7874 0.4064)
			(stroke
				(width 0.1524)
				(type default)
			)
			(layer "F.SilkS")
		)
		(fp_line
			(start -0.7874 -0.4064)
			(end 0.7874 -0.4064)
			(stroke
				(width 0.1524)
				(type default)
			)
			(layer "F.SilkS")
		)
		(fp_line
			(start 0.7874 0.4064)
			(end -0.7874 0.4064)
			(stroke
				(width 0.1524)
				(type default)
			)
			(layer "F.SilkS")
		)
		(fp_line
			(start -0.7874 0.4064)
			(end -0.7874 -0.4064)
			(stroke
				(width 0.1524)
				(type default)
			)
			(layer "F.SilkS")
		)
		(fp_line
			(start -0.12065 -0.305054)
			(end -0.12065 -0.2794)
			(stroke
				(width 0.1)
				(type default)
			)
			(layer "F.Fab")
		)
		(fp_line
			(start -0.67945 -0.305054)
			(end -0.12065 -0.305054)
			(stroke
				(width 0.1)
				(type default)
			)
			(layer "F.Fab")
		)
		(fp_line
			(start 0.67945 -0.3048)
			(end 0.67945 0.3048)
			(stroke
				(width 0.1)
				(type default)
			)
			(layer "F.Fab")
		)
		(fp_line
			(start 0.12065 -0.3048)
			(end 0.67945 -0.3048)
			(stroke
				(width 0.1)
				(type default)
			)
			(layer "F.Fab")
		)
		(fp_line
			(start 0.12065 -0.2794)
			(end 0.12065 -0.3048)
			(stroke
				(width 0.1)
				(type default)
			)
			(layer "F.Fab")
		)
		(fp_line
			(start -0.12065 -0.2794)
			(end 0.12065 -0.2794)
			(stroke
				(width 0.1)
				(type default)
			)
			(layer "F.Fab")
		)
		(fp_line
			(start 0.120396 0.2794)
			(end -0.12065 0.2794)
			(stroke
				(width 0.1)
				(type default)
			)
			(layer "F.Fab")
		)
		(fp_line
			(start -0.12065 0.2794)
			(end -0.12065 0.3048)
			(stroke
				(width 0.1)
				(type default)
			)
			(layer "F.Fab")
		)
		(fp_line
			(start 0.67945 0.3048)
			(end 0.120396 0.3048)
			(stroke
				(width 0.1)
				(type default)
			)
			(layer "F.Fab")
		)
		(fp_line
			(start 0.120396 0.3048)
			(end 0.120396 0.2794)
			(stroke
				(width 0.1)
				(type default)
			)
			(layer "F.Fab")
		)
		(fp_line
			(start -0.12065 0.3048)
			(end -0.67945 0.3048)
			(stroke
				(width 0.1)
				(type default)
			)
			(layer "F.Fab")
		)
		(fp_line
			(start -0.67945 0.3048)
			(end -0.67945 -0.305054)
			(stroke
				(width 0.1)
				(type default)
			)
			(layer "F.Fab")
		)
		(pad "1" smd circle
			(at -0.40005 0 90)
			(size 0 0)
			(layers "F.Cu" "F.Mask" "F.Paste")
			(net "P12V_AUX")
		)
		(pad "2" smd circle
			(at 0.40005 0 90)
			(size 0 0)
			(layers "F.Cu" "F.Mask" "F.Paste")
			(net "GND")
		)
	)
	(footprint ""
		(layer "F.Cu")
		(at 127.185166 -118.343426 -90)
		(property "Reference" "R5956"
			(at 0 0 270)
			(layer "F.SilkS")
			(hide yes)
			(effects
				(font
					(size 1.27 1.27)
				)
			)
		)
		(property "Value" ""
			(at 0 0 270)
			(layer "F.Fab")
			(effects
				(font
					(size 1.27 1.27)
				)
			)
		)
		(duplicate_pad_numbers_are_jumpers no)
		(fp_line
			(start -0.7874 0.4064)
			(end -0.7874 -0.4064)
			(stroke
				(width 0.1524)
				(type default)
			)
			(layer "F.SilkS")
		)
		(fp_line
			(start 0.7874 0.4064)
			(end -0.7874 0.4064)
			(stroke
				(width 0.1524)
				(type default)
			)
			(layer "F.SilkS")
		)
		(fp_line
			(start -0.7874 -0.4064)
			(end 0.7874 -0.4064)
			(stroke
				(width 0.1524)
				(type default)
			)
			(layer "F.SilkS")
		)
		(fp_line
			(start 0.7874 -0.4064)
			(end 0.7874 0.4064)
			(stroke
				(width 0.1524)
				(type default)
			)
			(layer "F.SilkS")
		)
		(fp_line
			(start -0.67945 0.3048)
			(end -0.67945 -0.305054)
			(stroke
				(width 0.1)
				(type default)
			)
			(layer "F.Fab")
		)
		(fp_line
			(start -0.12065 0.3048)
			(end -0.67945 0.3048)
			(stroke
				(width 0.1)
				(type default)
			)
			(layer "F.Fab")
		)
		(fp_line
			(start 0.120396 0.3048)
			(end 0.120396 0.2794)
			(stroke
				(width 0.1)
				(type default)
			)
			(layer "F.Fab")
		)
		(fp_line
			(start 0.67945 0.3048)
			(end 0.120396 0.3048)
			(stroke
				(width 0.1)
				(type default)
			)
			(layer "F.Fab")
		)
		(fp_line
			(start -0.12065 0.2794)
			(end -0.12065 0.3048)
			(stroke
				(width 0.1)
				(type default)
			)
			(layer "F.Fab")
		)
		(fp_line
			(start 0.120396 0.2794)
			(end -0.12065 0.2794)
			(stroke
				(width 0.1)
				(type default)
			)
			(layer "F.Fab")
		)
		(fp_line
			(start -0.12065 -0.2794)
			(end 0.12065 -0.2794)
			(stroke
				(width 0.1)
				(type default)
			)
			(layer "F.Fab")
		)
		(fp_line
			(start 0.12065 -0.2794)
			(end 0.12065 -0.3048)
			(stroke
				(width 0.1)
				(type default)
			)
			(layer "F.Fab")
		)
		(fp_line
			(start 0.12065 -0.3048)
			(end 0.67945 -0.3048)
			(stroke
				(width 0.1)
				(type default)
			)
			(layer "F.Fab")
		)
		(fp_line
			(start 0.67945 -0.3048)
			(end 0.67945 0.3048)
			(stroke
				(width 0.1)
				(type default)
			)
			(layer "F.Fab")
		)
		(fp_line
			(start -0.67945 -0.305054)
			(end -0.12065 -0.305054)
			(stroke
				(width 0.1)
				(type default)
			)
			(layer "F.Fab")
		)
		(fp_line
			(start -0.12065 -0.305054)
			(end -0.12065 -0.2794)
			(stroke
				(width 0.1)
				(type default)
			)
			(layer "F.Fab")
		)
		(pad "1" smd circle
			(at -0.40005 0 270)
			(size 0 0)
			(layers "F.Cu" "F.Mask" "F.Paste")
			(net "P3V3_AUX")
		)
		(pad "2" smd circle
			(at 0.40005 0 270)
			(size 0 0)
			(layers "F.Cu" "F.Mask" "F.Paste")
			(net "PWRGD_P3V3_NIC2_D")
		)
	)
	(footprint ""
		(layer "F.Cu")
		(at 141.71168 -71.458074 -90)
		(property "Reference" "PD105"
			(at 4.249674 -2.76479 90)
			(unlocked yes)
			(layer "F.SilkS")
			(effects
				(font
					(size 0.7874 0.5842)
					(thickness 0.1524)
				)
				(justify left)
			)
		)
		(property "Value" ""
			(at 0 0 270)
			(layer "F.Fab")
			(effects
				(font
					(size 1.27 1.27)
				)
			)
		)
		(duplicate_pad_numbers_are_jumpers no)
		(fp_line
			(start -3.656584 1.970024)
			(end 4.240784 1.970024)
			(stroke
				(width 0.1524)
				(type default)
			)
			(layer "F.SilkS")
		)
		(fp_line
			(start 4.240784 1.970024)
			(end 4.240784 -1.970024)
			(stroke
				(width 0.1524)
				(type default)
			)
			(layer "F.SilkS")
		)
		(fp_line
			(start -3.656584 -1.970024)
			(end -3.656584 1.970024)
			(stroke
				(width 0.1524)
				(type default)
			)
			(layer "F.SilkS")
		)
		(fp_line
			(start 4.240784 -1.970024)
			(end -3.656584 -1.970024)
			(stroke
				(width 0.1524)
				(type default)
			)
			(layer "F.SilkS")
		)
		(fp_poly
			(pts
				(xy 3.580384 1.970024) (xy 3.580384 -1.970024) (xy 4.240784 -1.970024) (xy 4.240784 1.970024)
			)
			(stroke
				(width 0)
				(type default)
			)
			(fill yes)
			(layer "F.SilkS")
		)
		(fp_line
			(start -2.3749 1.970024)
			(end 2.3749 1.970024)
			(stroke
				(width 0.1)
				(type default)
			)
			(layer "F.Fab")
		)
		(fp_line
			(start 2.3749 1.970024)
			(end 2.3749 -1.970024)
			(stroke
				(width 0.1)
				(type default)
			)
			(layer "F.Fab")
		)
		(fp_line
			(start -2.3749 -1.970024)
			(end -2.3749 1.970024)
			(stroke
				(width 0.1)
				(type default)
			)
			(layer "F.Fab")
		)
		(fp_line
			(start 2.3749 -1.970024)
			(end -2.3749 -1.970024)
			(stroke
				(width 0.1)
				(type default)
			)
			(layer "F.Fab")
		)
		(fp_text user "+"
			(at -4.9784 -0.23495 270)
			(unlocked yes)
			(layer "F.Fab")
			(effects
				(font
					(size 1.905 1.4224)
					(thickness 0.1524)
				)
				(justify left)
			)
		)
		(fp_text user "-"
			(at 4.1656 -0.23495 270)
			(unlocked yes)
			(layer "F.Fab")
			(effects
				(font
					(size 1.905 1.4224)
					(thickness 0.1524)
				)
				(justify left)
			)
		)
		(pad "A" smd rect
			(at -2.450084 0 270)
			(size 2.159 2.2606)
			(layers "F.Cu" "F.Mask" "F.Paste")
			(net "GND")
		)
		(pad "C" smd rect
			(at 2.450084 0 270)
			(size 2.159 2.2606)
			(layers "F.Cu" "F.Mask" "F.Paste")
			(net "P12V_AUX")
		)
	)
	(footprint ""
		(layer "F.Cu")
		(at 264.611358 -280.443432 -90)
		(property "Reference" "R4586"
			(at 0 0 270)
			(layer "F.SilkS")
			(hide yes)
			(effects
				(font
					(size 1.27 1.27)
				)
			)
		)
		(property "Value" ""
			(at 0 0 270)
			(layer "F.Fab")
			(effects
				(font
					(size 1.27 1.27)
				)
			)
		)
		(duplicate_pad_numbers_are_jumpers no)
		(fp_line
			(start -0.7874 0.4064)
			(end -0.7874 -0.4064)
			(stroke
				(width 0.1524)
				(type default)
			)
			(layer "F.SilkS")
		)
		(fp_line
			(start 0.7874 0.4064)
			(end -0.7874 0.4064)
			(stroke
				(width 0.1524)
				(type default)
			)
			(layer "F.SilkS")
		)
		(fp_line
			(start -0.7874 -0.4064)
			(end 0.7874 -0.4064)
			(stroke
				(width 0.1524)
				(type default)
			)
			(layer "F.SilkS")
		)
		(fp_line
			(start 0.7874 -0.4064)
			(end 0.7874 0.4064)
			(stroke
				(width 0.1524)
				(type default)
			)
			(layer "F.SilkS")
		)
		(fp_line
			(start -0.67945 0.3048)
			(end -0.67945 -0.305054)
			(stroke
				(width 0.1)
				(type default)
			)
			(layer "F.Fab")
		)
		(fp_line
			(start -0.12065 0.3048)
			(end -0.67945 0.3048)
			(stroke
				(width 0.1)
				(type default)
			)
			(layer "F.Fab")
		)
		(fp_line
			(start 0.120396 0.3048)
			(end 0.120396 0.2794)
			(stroke
				(width 0.1)
				(type default)
			)
			(layer "F.Fab")
		)
		(fp_line
			(start 0.67945 0.3048)
			(end 0.120396 0.3048)
			(stroke
				(width 0.1)
				(type default)
			)
			(layer "F.Fab")
		)
		(fp_line
			(start -0.12065 0.2794)
			(end -0.12065 0.3048)
			(stroke
				(width 0.1)
				(type default)
			)
			(layer "F.Fab")
		)
		(fp_line
			(start 0.120396 0.2794)
			(end -0.12065 0.2794)
			(stroke
				(width 0.1)
				(type default)
			)
			(layer "F.Fab")
		)
		(fp_line
			(start -0.12065 -0.2794)
			(end 0.12065 -0.2794)
			(stroke
				(width 0.1)
				(type default)
			)
			(layer "F.Fab")
		)
		(fp_line
			(start 0.12065 -0.2794)
			(end 0.12065 -0.3048)
			(stroke
				(width 0.1)
				(type default)
			)
			(layer "F.Fab")
		)
		(fp_line
			(start 0.12065 -0.3048)
			(end 0.67945 -0.3048)
			(stroke
				(width 0.1)
				(type default)
			)
			(layer "F.Fab")
		)
		(fp_line
			(start 0.67945 -0.3048)
			(end 0.67945 0.3048)
			(stroke
				(width 0.1)
				(type default)
			)
			(layer "F.Fab")
		)
		(fp_line
			(start -0.67945 -0.305054)
			(end -0.12065 -0.305054)
			(stroke
				(width 0.1)
				(type default)
			)
			(layer "F.Fab")
		)
		(fp_line
			(start -0.12065 -0.305054)
			(end -0.12065 -0.2794)
			(stroke
				(width 0.1)
				(type default)
			)
			(layer "F.Fab")
		)
		(pad "1" smd circle
			(at -0.40005 0 270)
			(size 0 0)
			(layers "F.Cu" "F.Mask" "F.Paste")
			(net "SYSPLL_VDDA18_PEX2")
		)
		(pad "2" smd circle
			(at 0.40005 0 270)
			(size 0 0)
			(layers "F.Cu" "F.Mask" "F.Paste")
			(net "SYSPLL_VDDA18_PEX2_R")
		)
	)
	(footprint ""
		(layer "F.Cu")
		(at 43.792394 -32.739584 180)
		(property "Reference" "C75"
			(at 0 0 180)
			(layer "F.SilkS")
			(hide yes)
			(effects
				(font
					(size 1.27 1.27)
				)
			)
		)
		(property "Value" ""
			(at 0 0 180)
			(layer "F.Fab")
			(effects
				(font
					(size 1.27 1.27)
				)
			)
		)
		(duplicate_pad_numbers_are_jumpers no)
		(fp_line
			(start 0.299974 0.150114)
			(end -0.299974 0.150114)
			(stroke
				(width 0.1)
				(type default)
			)
			(layer "F.Fab")
		)
		(fp_line
			(start 0.299974 -0.150114)
			(end 0.299974 0.150114)
			(stroke
				(width 0.1)
				(type default)
			)
			(layer "F.Fab")
		)
		(fp_line
			(start -0.299974 0.150114)
			(end -0.299974 -0.150114)
			(stroke
				(width 0.1)
				(type default)
			)
			(layer "F.Fab")
		)
		(fp_line
			(start -0.299974 -0.150114)
			(end 0.299974 -0.150114)
			(stroke
				(width 0.1)
				(type default)
			)
			(layer "F.Fab")
		)
		(pad "1" smd rect
			(at -0.2667 0 180)
			(size 0.3048 0.381)
			(layers "F.Cu" "F.Mask" "F.Paste")
			(net "P5E_PEX0_STN2_TX_DP<42>")
		)
		(pad "2" smd rect
			(at 0.2667 0 180)
			(size 0.3048 0.381)
			(layers "F.Cu" "F.Mask" "F.Paste")
			(net "P5E_PEX0_STN2_TX_C_DP<42>")
		)
	)
	(footprint ""
		(layer "F.Cu")
		(at 99.023678 -106.413808 180)
		(property "Reference" "PD79"
			(at 4.230878 2.093722 0)
			(unlocked yes)
			(layer "F.SilkS")
			(effects
				(font
					(size 0.7874 0.5842)
					(thickness 0.1524)
				)
				(justify left)
			)
		)
		(property "Value" ""
			(at 0 0 180)
			(layer "F.Fab")
			(effects
				(font
					(size 1.27 1.27)
				)
			)
		)
		(duplicate_pad_numbers_are_jumpers no)
		(fp_line
			(start 4.107942 1.459992)
			(end -3.400044 1.459992)
			(stroke
				(width 0.1524)
				(type default)
			)
			(layer "F.SilkS")
		)
		(fp_line
			(start 4.107942 -1.459992)
			(end 4.107942 1.459992)
			(stroke
				(width 0.1524)
				(type default)
			)
			(layer "F.SilkS")
		)
		(fp_line
			(start -3.400044 1.459992)
			(end -3.400044 -1.459992)
			(stroke
				(width 0.1524)
				(type default)
			)
			(layer "F.SilkS")
		)
		(fp_line
			(start -3.400044 -1.459992)
			(end 4.107942 -1.459992)
			(stroke
				(width 0.1524)
				(type default)
			)
			(layer "F.SilkS")
		)
		(fp_rect
			(start 4.107942 -1.459992)
			(end 3.308096 1.459992)
			(stroke
				(width 0)
				(type default)
			)
			(fill yes)
			(layer "F.SilkS")
		)
		(fp_line
			(start 2.29997 1.459992)
			(end -2.29997 1.459992)
			(stroke
				(width 0.1)
				(type default)
			)
			(layer "F.Fab")
		)
		(fp_line
			(start 2.29997 -1.459992)
			(end 2.29997 1.459992)
			(stroke
				(width 0.1)
				(type default)
			)
			(layer "F.Fab")
		)
		(fp_line
			(start -2.29997 1.459992)
			(end -2.29997 -1.459992)
			(stroke
				(width 0.1)
				(type default)
			)
			(layer "F.Fab")
		)
		(fp_line
			(start -2.29997 -1.459992)
			(end 2.29997 -1.459992)
			(stroke
				(width 0.1)
				(type default)
			)
			(layer "F.Fab")
		)
		(fp_text user "-"
			(at 4.38531 -1.64592 0)
			(unlocked yes)
			(layer "F.SilkS")
			(effects
				(font
					(size 1.905 1.4224)
					(thickness 0.1524)
				)
				(justify left)
			)
		)
		(fp_text user "+"
			(at -4.586986 0.916432 180)
			(unlocked yes)
			(layer "F.SilkS")
			(effects
				(font
					(size 1.905 1.4224)
					(thickness 0.1524)
				)
				(justify left)
			)
		)
		(fp_text user "-"
			(at 5.4102 0.29845 0)
			(unlocked yes)
			(layer "F.Fab")
			(effects
				(font
					(size 1.905 1.4224)
					(thickness 0.1524)
				)
				(justify left)
			)
		)
		(fp_text user "+"
			(at -4.7752 -0.12065 180)
			(unlocked yes)
			(layer "F.Fab")
			(effects
				(font
					(size 1.905 1.4224)
					(thickness 0.1524)
				)
				(justify left)
			)
		)
		(pad "A" smd rect
			(at -1.999996 0 270)
			(size 1.7018 2.5146)
			(layers "F.Cu" "F.Mask" "F.Paste")
			(net "GND")
		)
		(pad "C" smd rect
			(at 1.999996 0 270)
			(size 1.7018 2.5146)
			(layers "F.Cu" "F.Mask" "F.Paste")
			(net "P12V_NIC1_R")
		)
	)
	(footprint ""
		(layer "F.Cu")
		(at 204.849476 -377.025916)
		(property "Reference" "R6252"
			(at 0 0 0)
			(layer "F.SilkS")
			(hide yes)
			(effects
				(font
					(size 1.27 1.27)
				)
			)
		)
		(property "Value" ""
			(at 0 0 0)
			(layer "F.Fab")
			(effects
				(font
					(size 1.27 1.27)
				)
			)
		)
		(duplicate_pad_numbers_are_jumpers no)
		(fp_line
			(start -0.7874 -0.4064)
			(end 0.7874 -0.4064)
			(stroke
				(width 0.1524)
				(type default)
			)
			(layer "F.SilkS")
		)
		(fp_line
			(start -0.7874 0.4064)
			(end -0.7874 -0.4064)
			(stroke
				(width 0.1524)
				(type default)
			)
			(layer "F.SilkS")
		)
		(fp_line
			(start 0.7874 -0.4064)
			(end 0.7874 0.4064)
			(stroke
				(width 0.1524)
				(type default)
			)
			(layer "F.SilkS")
		)
		(fp_line
			(start 0.7874 0.4064)
			(end -0.7874 0.4064)
			(stroke
				(width 0.1524)
				(type default)
			)
			(layer "F.SilkS")
		)
		(fp_line
			(start -0.67945 -0.305054)
			(end -0.12065 -0.305054)
			(stroke
				(width 0.1)
				(type default)
			)
			(layer "F.Fab")
		)
		(fp_line
			(start -0.67945 0.3048)
			(end -0.67945 -0.305054)
			(stroke
				(width 0.1)
				(type default)
			)
			(layer "F.Fab")
		)
		(fp_line
			(start -0.12065 -0.305054)
			(end -0.12065 -0.2794)
			(stroke
				(width 0.1)
				(type default)
			)
			(layer "F.Fab")
		)
		(fp_line
			(start -0.12065 -0.2794)
			(end 0.12065 -0.2794)
			(stroke
				(width 0.1)
				(type default)
			)
			(layer "F.Fab")
		)
		(fp_line
			(start -0.12065 0.2794)
			(end -0.12065 0.3048)
			(stroke
				(width 0.1)
				(type default)
			)
			(layer "F.Fab")
		)
		(fp_line
			(start -0.12065 0.3048)
			(end -0.67945 0.3048)
			(stroke
				(width 0.1)
				(type default)
			)
			(layer "F.Fab")
		)
		(fp_line
			(start 0.120396 0.2794)
			(end -0.12065 0.2794)
			(stroke
				(width 0.1)
				(type default)
			)
			(layer "F.Fab")
		)
		(fp_line
			(start 0.120396 0.3048)
			(end 0.120396 0.2794)
			(stroke
				(width 0.1)
				(type default)
			)
			(layer "F.Fab")
		)
		(fp_line
			(start 0.12065 -0.3048)
			(end 0.67945 -0.3048)
			(stroke
				(width 0.1)
				(type default)
			)
			(layer "F.Fab")
		)
		(fp_line
			(start 0.12065 -0.2794)
			(end 0.12065 -0.3048)
			(stroke
				(width 0.1)
				(type default)
			)
			(layer "F.Fab")
		)
		(fp_line
			(start 0.67945 -0.3048)
			(end 0.67945 0.3048)
			(stroke
				(width 0.1)
				(type default)
			)
			(layer "F.Fab")
		)
		(fp_line
			(start 0.67945 0.3048)
			(end 0.120396 0.3048)
			(stroke
				(width 0.1)
				(type default)
			)
			(layer "F.Fab")
		)
		(pad "1" smd circle
			(at -0.40005 0)
			(size 0 0)
			(layers "F.Cu" "F.Mask" "F.Paste")
			(net "MB_HSC_ISO_D1_EN")
		)
		(pad "2" smd circle
			(at 0.40005 0)
			(size 0 0)
			(layers "F.Cu" "F.Mask" "F.Paste")
			(net "P12V_STBY")
		)
	)
)
